#ISCELL
  pure_quanta quanta_title_block_c *
  *
#ISCELL
  standard offpage *
  page215_i10
#ISCELL
  standard offpage *
  page215_i11
#CELL
  pure_quanta q_res *
  page215_i12
#CELL
  pure_quanta q_res *
  page215_i13
#ISCELL
  standard offpage *
  page215_i14
#ISCELL
  standard offpage *
  page215_i15
#ISCELL
  standard offpage *
  page215_i17
#ISCELL
  standard offpage *
  page215_i18
#ISCELL
  standard offpage *
  page215_i19
#CELL
  pure_quanta q_res *
  page215_i2
#ISCELL
  standard offpage *
  page215_i20
#ISCELL
  logical_power universal_gnd *
  page215_i21
#CELL
  pure_quanta q_res *
  page215_i23
#ISCELL
  standard offpage *
  page215_i24
#ISCELL
  standard offpage *
  page215_i26
#ISCELL
  logical_power universal_gnd *
  page215_i27
#CELL
  pure_quanta q_res *
  page215_i28
#ISCELL
  standard offpage *
  page215_i29
#ISCELL
  standard offpage *
  page215_i3
#ISCELL
  standard offpage *
  page215_i30
#ISCELL
  standard offpage *
  page215_i31
#CELL
  pure_quanta sconn20_513860200cv01 *
  page215_i32
#ISCELL
  standard offpage *
  page215_i4
#ISCELL
  standard offpage *
  page215_i5
#ISCELL
  standard offpage *
  page215_i6
#ISCELL
  standard offpage *
  page215_i7
#ISCELL
  standard offpage *
  page215_i8
#ISCELL
  standard offpage *
  page215_i9
